# environment-sensor — KiCad project settings (.kicad_pro: net classes, design rules, text variables)
{
  "board": {
    "3dviewports": [],
    "design_settings": {
      "defaults": {
        "board_outline_line_width": 0.09999999999999999,
        "copper_line_width": 0.19999999999999998,
        "copper_text_italic": false,
        "copper_text_size_h": 1.5,
        "copper_text_size_v": 1.5,
        "copper_text_thickness": 0.3,
        "copper_text_upright": false,
        "courtyard_line_width": 0.049999999999999996,
        "dimension_precision": 4,
        "dimension_units": 3,
        "dimensions": {
          "arrow_length": 1270000,
          "extension_offset": 500000,
          "keep_text_aligned": true,
          "suppress_zeroes": false,
          "text_position": 0,
          "units_format": 1
        },
        "fab_line_width": 0.09999999999999999,
        "fab_text_italic": false,
        "fab_text_size_h": 1.0,
        "fab_text_size_v": 1.0,
        "fab_text_thickness": 0.15,
        "fab_text_upright": false,
        "other_line_width": 0.15,
        "other_text_italic": false,
        "other_text_size_h": 1.0,
        "other_text_size_v": 1.0,
        "other_text_thickness": 0.15,
        "other_text_upright": false,
        "pads": {
          "drill": 0.0,
          "height": 1.5,
          "width": 1.5
        },
        "silk_line_width": 0.15,
        "silk_text_italic": false,
        "silk_text_size_h": 1.0,
        "silk_text_size_v": 1.0,
        "silk_text_thickness": 0.15,
        "silk_text_upright": false,
        "zones": {
          "45_degree_only": false,
          "min_clearance": 0.25
        }
      },
      "diff_pair_dimensions": [
        {
          "gap": 0.0,
          "via_gap": 0.0,
          "width": 0.0
        }
      ],
      "drc_exclusions": [],
      "meta": {
        "version": 2
      },
      "rule_severities": {
        "annular_width": "error",
        "clearance": "error",
        "connection_width": "warning",
        "copper_edge_clearance": "error",
        "copper_sliver": "warning",
        "courtyards_overlap": "error",
        "diff_pair_gap_out_of_range": "error",
        "diff_pair_uncoupled_length_too_long": "error",
        "drill_out_of_range": "error",
        "duplicate_footprints": "warning",
        "extra_footprint": "warning",
        "footprint": "error",
        "footprint_type_mismatch": "error",
        "hole_clearance": "error",
        "hole_near_hole": "error",
        "invalid_outline": "error",
        "isolated_copper": "warning",
        "item_on_disabled_layer": "error",
        "items_not_allowed": "error",
        "length_out_of_range": "error",
        "lib_footprint_issues": "warning",
        "lib_footprint_mismatch": "warning",
        "malformed_courtyard": "error",
        "microvia_drill_out_of_range": "error",
        "missing_courtyard": "ignore",
        "missing_footprint": "warning",
        "net_conflict": "warning",
        "npth_inside_courtyard": "ignore",
        "padstack": "error",
        "pth_inside_courtyard": "ignore",
        "shorting_items": "error",
        "silk_edge_clearance": "warning",
        "silk_over_copper": "warning",
        "silk_overlap": "warning",
        "skew_out_of_range": "error",
        "solder_mask_bridge": "error",
        "starved_thermal": "error",
        "text_height": "warning",
        "text_thickness": "warning",
        "through_hole_pad_without_hole": "error",
        "too_many_vias": "error",
        "track_dangling": "warning",
        "track_width": "error",
        "tracks_crossing": "error",
        "unconnected_items": "error",
        "unresolved_variable": "error",
        "via_dangling": "warning",
        "zones_intersect": "error"
      },
      "rules": {
        "allow_blind_buried_vias": false,
        "allow_microvias": false,
        "max_error": 0.005,
        "min_clearance": 0.15,
        "min_connection": 0.0,
        "min_copper_edge_clearance": 0.0,
        "min_hole_clearance": 0.15,
        "min_hole_to_hole": 0.25,
        "min_microvia_diameter": 0.19999999999999998,
        "min_microvia_drill": 0.09999999999999999,
        "min_resolved_spokes": 1,
        "min_silk_clearance": 0.0,
        "min_text_height": 0.65,
        "min_text_thickness": 0.08,
        "min_through_hole_diameter": 0.19999999999999998,
        "min_track_width": 0.15,
        "min_via_annular_width": 0.049999999999999996,
        "min_via_diameter": 0.5,
        "solder_mask_clearance": 0.0,
        "solder_mask_min_width": 0.0,
        "solder_mask_to_copper_clearance": 0.0,
        "use_height_for_length_calcs": true
      },
      "teardrop_options": [
        {
          "td_allow_use_two_tracks": true,
          "td_curve_segcount": 5,
          "td_on_pad_in_zone": false,
          "td_onpadsmd": true,
          "td_onroundshapesonly": false,
          "td_ontrackend": false,
          "td_onviapad": true
        }
      ],
      "teardrop_parameters": [
        {
          "td_curve_segcount": 0,
          "td_height_ratio": 1.0,
          "td_length_ratio": 0.5,
          "td_maxheight": 2.0,
          "td_maxlen": 1.0,
          "td_target_name": "td_round_shape",
          "td_width_to_size_filter_ratio": 0.9
        },
        {
          "td_curve_segcount": 0,
          "td_height_ratio": 1.0,
          "td_length_ratio": 0.5,
          "td_maxheight": 2.0,
          "td_maxlen": 1.0,
          "td_target_name": "td_rect_shape",
          "td_width_to_size_filter_ratio": 0.9
        },
        {
          "td_curve_segcount": 0,
          "td_height_ratio": 1.0,
          "td_length_ratio": 0.5,
          "td_maxheight": 2.0,
          "td_maxlen": 1.0,
          "td_target_name": "td_track_end",
          "td_width_to_size_filter_ratio": 0.9
        }
      ],
      "track_widths": [
        0.0
      ],
      "via_dimensions": [
        {
          "diameter": 0.0,
          "drill": 0.0
        }
      ],
      "zones_allow_external_fillets": false,
      "zones_use_no_outline": true
    },
    "ipc2581": {
      "dist": "",
      "distpn": "",
      "internal_id": "",
      "mfg": "",
      "mpn": ""
    },
    "layer_pairs": [],
    "layer_presets": [],
    "viewports": []
  },
  "boards": [],
  "cvpcb": {
    "equivalence_files": []
  },
  "erc": {
    "erc_exclusions": [],
    "meta": {
      "version": 0
    },
    "pin_map": [
      [
        0,
        0,
        0,
        0,
        0,
        0,
        1,
        0,
        0,
        0,
        0,
        2
      ],
      [
        0,
        2,
        0,
        1,
        0,
        0,
        1,
        0,
        2,
        2,
        2,
        2
      ],
      [
        0,
        0,
        0,
        0,
        0,
        0,
        1,
        0,
        1,
        0,
        1,
        2
      ],
      [
        0,
        1,
        0,
        0,
        0,
        0,
        1,
        1,
        2,
        1,
        1,
        2
      ],
      [
        0,
        0,
        0,
        0,
        0,
        0,
        1,
        0,
        0,
        0,
        0,
        2
      ],
      [
        0,
        0,
        0,
        0,
        0,
        0,
        0,
        0,
        0,
        0,
        0,
        2
      ],
      [
        1,
        1,
        1,
        1,
        1,
        0,
        1,
        1,
        1,
        1,
        1,
        2
      ],
      [
        0,
        0,
        0,
        1,
        0,
        0,
        1,
        0,
        0,
        0,
        0,
        2
      ],
      [
        0,
        2,
        1,
        2,
        0,
        0,
        1,
        0,
        2,
        2,
        2,
        2
      ],
      [
        0,
        2,
        0,
        1,
        0,
        0,
        1,
        0,
        2,
        0,
        0,
        2
      ],
      [
        0,
        2,
        1,
        1,
        0,
        0,
        1,
        0,
        2,
        0,
        0,
        2
      ],
      [
        2,
        2,
        2,
        2,
        2,
        2,
        2,
        2,
        2,
        2,
        2,
        2
      ]
    ],
    "rule_severities": {
      "bus_definition_conflict": "error",
      "bus_entry_needed": "error",
      "bus_to_bus_conflict": "error",
      "bus_to_net_conflict": "error",
      "conflicting_netclasses": "error",
      "different_unit_footprint": "error",
      "different_unit_net": "error",
      "duplicate_reference": "error",
      "duplicate_sheet_names": "error",
      "endpoint_off_grid": "warning",
      "extra_units": "error",
      "footprint_filter": "ignore",
      "footprint_link_issues": "warning",
      "four_way_junction": "ignore",
      "global_label_dangling": "warning",
      "hier_label_mismatch": "error",
      "label_dangling": "error",
      "label_multiple_wires": "warning",
      "lib_symbol_issues": "warning",
      "lib_symbol_mismatch": "warning",
      "missing_bidi_pin": "warning",
      "missing_input_pin": "warning",
      "missing_power_pin": "error",
      "missing_unit": "warning",
      "multiple_net_names": "warning",
      "net_not_bus_member": "warning",
      "no_connect_connected": "warning",
      "no_connect_dangling": "warning",
      "pin_not_connected": "error",
      "pin_not_driven": "error",
      "pin_to_pin": "warning",
      "power_pin_not_driven": "error",
      "same_local_global_label": "warning",
      "similar_label_and_power": "warning",
      "similar_labels": "warning",
      "similar_power": "warning",
      "simulation_model_issue": "ignore",
      "single_global_label": "ignore",
      "unannotated": "error",
      "unconnected_wire_endpoint": "warning",
      "unit_value_mismatch": "error",
      "unresolved_variable": "error",
      "wire_dangling": "error"
    }
  },
  "libraries": {
    "pinned_footprint_libs": [],
    "pinned_symbol_libs": []
  },
  "meta": {
    "filename": "environment-sensor.kicad_pro",
    "version": 3
  },
  "net_settings": {
    "classes": [
      {
        "bus_width": 12,
        "clearance": 0.15,
        "diff_pair_gap": 0.25,
        "diff_pair_via_gap": 0.25,
        "diff_pair_width": 0.2,
        "line_style": 0,
        "microvia_diameter": 0.3,
        "microvia_drill": 0.1,
        "name": "Default",
        "pcb_color": "rgba(0, 0, 0, 0.000)",
        "priority": 2147483647,
        "schematic_color": "rgba(0, 0, 0, 0.000)",
        "track_width": 0.15,
        "via_diameter": 0.6,
        "via_drill": 0.25,
        "wire_width": 6
      },
      {
        "bus_width": 12,
        "clearance": 0.15,
        "diff_pair_gap": 0.196,
        "diff_pair_via_gap": 0.25,
        "diff_pair_width": 0.182,
        "line_style": 0,
        "microvia_diameter": 0.3,
        "microvia_drill": 0.1,
        "name": "90Ohm-diff_USB",
        "pcb_color": "rgba(0, 0, 0, 0.000)",
        "priority": 0,
        "schematic_color": "rgba(0, 0, 0, 0.000)",
        "track_width": 0.182,
        "via_diameter": 0.6,
        "via_drill": 0.25,
        "wire_width": 6
      },
      {
        "bus_width": 12,
        "clearance": 0.15,
        "diff_pair_gap": 0.75,
        "diff_pair_via_gap": 0.25,
        "diff_pair_width": 0.15,
        "line_style": 0,
        "microvia_diameter": 0.3,
        "microvia_drill": 0.1,
        "name": "I2C",
        "pcb_color": "rgba(0, 0, 0, 0.000)",
        "priority": 1,
        "schematic_color": "rgba(0, 0, 0, 0.000)",
        "track_width": 0.15,
        "via_diameter": 0.6,
        "via_drill": 0.25,
        "wire_width": 6
      },
      {
        "bus_width": 12,
        "clearance": 0.15,
        "diff_pair_gap": 0.25,
        "diff_pair_via_gap": 0.25,
        "diff_pair_width": 0.2,
        "line_style": 0,
        "microvia_diameter": 0.3,
        "microvia_drill": 0.1,
        "name": "Power",
        "pcb_color": "rgba(0, 0, 0, 0.000)",
        "priority": 2,
        "schematic_color": "rgba(0, 0, 0, 0.000)",
        "track_width": 0.25,
        "via_diameter": 0.6,
        "via_drill": 0.25,
        "wire_width": 6
      }
    ],
    "meta": {
      "version": 4
    },
    "net_colors": null,
    "netclass_assignments": null,
    "netclass_patterns": []
  },
  "pcbnew": {
    "last_paths": {
      "gencad": "",
      "idf": "",
      "netlist": "",
      "plot": "",
      "pos_files": "",
      "specctra_dsn": "",
      "step": "",
      "svg": "",
      "vrml": ""
    },
    "page_layout_descr_file": ""
  },
  "schematic": {
    "annotate_start_num": 0,
    "bom_export_filename": "${PROJECTNAME}.csv",
    "bom_fmt_presets": [],
    "bom_fmt_settings": {
      "field_delimiter": ",",
      "keep_line_breaks": false,
      "keep_tabs": false,
      "name": "CSV",
      "ref_delimiter": ",",
      "ref_range_delimiter": "",
      "string_delimiter": "\""
    },
    "bom_presets": [],
    "bom_settings": {
      "exclude_dnp": false,
      "fields_ordered": [
        {
          "group_by": false,
          "label": "Reference",
          "name": "Reference",
          "show": true
        },
        {
          "group_by": false,
          "label": "Qty",
          "name": "${QUANTITY}",
          "show": true
        },
        {
          "group_by": true,
          "label": "Value",
          "name": "Value",
          "show": true
        },
        {
          "group_by": true,
          "label": "DNP",
          "name": "${DNP}",
          "show": true
        },
        {
          "group_by": true,
          "label": "Exclude from BOM",
          "name": "${EXCLUDE_FROM_BOM}",
          "show": true
        },
        {
          "group_by": true,
          "label": "Exclude from Board",
          "name": "${EXCLUDE_FROM_BOARD}",
          "show": true
        },
        {
          "group_by": true,
          "label": "Footprint",
          "name": "Footprint",
          "show": true
        },
        {
          "group_by": false,
          "label": "Datasheet",
          "name": "Datasheet",
          "show": true
        }
      ],
      "filter_string": "",
      "group_symbols": true,
      "include_excluded_from_bom": true,
      "name": "Default Editing",
      "sort_asc": true,
      "sort_field": "Reference"
    },
    "connection_grid_size": 50.0,
    "drawing": {
      "dashed_lines_dash_length_ratio": 12.0,
      "dashed_lines_gap_length_ratio": 3.0,
      "default_line_thickness": 6.0,
      "default_text_size": 50.0,
      "field_names": [],
      "intersheets_ref_own_page": false,
      "intersheets_ref_prefix": "",
      "intersheets_ref_short": false,
      "intersheets_ref_show": false,
      "intersheets_ref_suffix": "",
      "junction_size_choice": 3,
      "label_size_ratio": 0.375,
      "operating_point_overlay_i_precision": 3,
      "operating_point_overlay_i_range": "~A",
      "operating_point_overlay_v_precision": 3,
      "operating_point_overlay_v_range": "~V",
      "overbar_offset_ratio": 1.23,
      "pin_symbol_size": 25.0,
      "text_offset_ratio": 0.15
    },
    "legacy_lib_dir": "",
    "legacy_lib_list": [],
    "meta": {
      "version": 1
    },
    "net_format_name": "",
    "ngspice": {
      "fix_include_paths": true,
      "fix_passive_vals": false,
      "meta": {
        "version": 0
      },
      "model_mode": 0,
      "workbook_filename": ""
    },
    "page_layout_descr_file": "",
    "plot_directory": "doc/",
    "space_save_all_events": true,
    "spice_adjust_passive_values": false,
    "spice_current_sheet_as_root": false,
    "spice_external_command": "spice \"%I\"",
    "spice_model_current_sheet_as_root": true,
    "spice_save_all_currents": false,
    "spice_save_all_dissipations": false,
    "spice_save_all_voltages": false,
    "subpart_first_id": 65,
    "subpart_id_separator": 0
  },
  "sheets": [
    [
      "",
      "Root"
    ]
  ],
  "text_variables": {}
}
